# TIMECARD (Time Appliance Project (Time Card)) — schematic netlist excerpt (pin names and nets, part order shuffled) for the footprints in the layout excerpt that follows; sources: Cadence DE-HDL packaged netlist, KiCad conversion of R4006-B0001-02_R01.brd

L10  FERRITEBEAD  600OHM 25%  pkg SMC_0603R_H037  page 15 : \1\ = VDD3V3_OSC_125M ; \2\ = XP3R3V
R191  RESISTOR  4.7KOHM 1%  pkg SMC_0402R_H016  page 10 : \1\ = XP3R3V_FPGA ; \2\ = FLASH_CS_N

(kicad_pcb
	(version 20260206)
	(generator "pcbnew")
	(generator_version "10.0")
	(general
		(thickness 1.6)
		(legacy_teardrops no)
	)
	(paper "A4")
	(title_block
		(title "timecard-production-celestica-r4006 — R4006-B0001-02_R01.brd")
		(comment 1 "Time Appliance Project (Time Card) / footprints 833-834 of 1113")
	)
	(layers
		(0 "F.Cu" signal "TOP")
		(4 "In1.Cu" signal "L02_GND1")
		(6 "In2.Cu" signal "L03_SIG1")
		(8 "In3.Cu" signal "L04_GND2")
		(10 "In4.Cu" signal "L05_VCC1")
		(12 "In5.Cu" signal "L06_VCC2")
		(14 "In6.Cu" signal "L07_GND3")
		(16 "In7.Cu" signal "L08_SIG2")
		(18 "In8.Cu" signal "L09_GND4")
		(2 "B.Cu" signal "BOTTOM")
		(9 "F.Adhes" user "F.Adhesive")
		(11 "B.Adhes" user "B.Adhesive")
		(13 "F.Paste" user "Package Geometry/Pastemask Top")
		(15 "B.Paste" user "Package Geometry/Pastemask Bottom")
		(5 "F.SilkS" user "Ref Des/Silkscreen Top")
		(7 "B.SilkS" user "Ref Des/Silkscreen Bottom")
		(1 "F.Mask" user "Board Geometry/Soldermask Top")
		(3 "B.Mask" user "Board Geometry/Soldermask Bottom")
		(17 "Dwgs.User" user "User.Drawings")
		(19 "Cmts.User" user "User.Comments")
		(21 "Eco1.User" user "User.Eco1")
		(23 "Eco2.User" user "User.Eco2")
		(25 "Edge.Cuts" user "Board Geometry/Outline")
		(27 "Margin" user)
		(31 "F.CrtYd" user "Package Geometry/Place Bound Top")
		(29 "B.CrtYd" user "Package Geometry/Place Bound Bottom")
		(35 "F.Fab" user "Ref Des/Assembly Top")
		(33 "B.Fab" user "Ref Des/Assembly Bottom")
	)
	(footprint ""
		(layer "B.Cu")
		(at 95.758 -22.606 90)
		(property "Reference" "L10"
			(at 0 2.25425 270)
			(unlocked yes)
			(layer "B.SilkS")
			(effects
				(font
					(size 0.635 0.4064)
					(thickness 0.1524)
				)
				(justify mirror)
			)
		)
		(property "Value" "VAL*"
			(at -0.014732 2.526538 90)
			(unlocked yes)
			(layer "B.Fab")
			(hide yes)
			(effects
				(font
					(size 0.7874 0.5842)
					(thickness 0.000001)
				)
				(justify mirror)
			)
		)
		(property "Device Type" "FERRITEBEAD-G191-10097-01,600OA"
			(at -0.014732 1.600708 90)
			(unlocked yes)
			(layer "B.Fab")
			(hide yes)
			(effects
				(font
					(size 0.7874 0.5842)
					(thickness 0.000001)
				)
				(justify mirror)
			)
		)
		(property "User Part Number" "PARTNUM*"
			(at -0.02794 4.480814 90)
			(unlocked yes)
			(layer "Cmts.User")
			(hide yes)
			(effects
				(font
					(size 0.7874 0.5842)
					(thickness 0.000001)
				)
				(justify mirror)
			)
		)
		(property "Tolerance" "TOL*"
			(at -0.014732 3.503676 90)
			(unlocked yes)
			(layer "Cmts.User")
			(hide yes)
			(effects
				(font
					(size 0.7874 0.5842)
					(thickness 0.000001)
				)
				(justify mirror)
			)
		)
		(duplicate_pad_numbers_are_jumpers no)
		(fp_line
			(start 1.3208 -0.7112)
			(end -1.3208 -0.7112)
			(stroke
				(width 0.1)
				(type default)
			)
			(layer "B.SilkS")
		)
		(fp_line
			(start -1.3208 -0.7112)
			(end -1.3208 0.7112)
			(stroke
				(width 0.1)
				(type default)
			)
			(layer "B.SilkS")
		)
		(fp_line
			(start 1.3208 0.7112)
			(end 1.3208 -0.7112)
			(stroke
				(width 0.1)
				(type default)
			)
			(layer "B.SilkS")
		)
		(fp_line
			(start -1.3208 0.7112)
			(end 1.3208 0.7112)
			(stroke
				(width 0.1)
				(type default)
			)
			(layer "B.SilkS")
		)
		(fp_rect
			(start 1.3208 0.7112)
			(end -1.3208 -0.7112)
			(stroke
				(width 0)
				(type default)
			)
			(fill no)
			(layer "B.CrtYd")
		)
		(fp_line
			(start 0.8128 -0.4572)
			(end -0.8128 -0.4572)
			(stroke
				(width 0.1)
				(type default)
			)
			(layer "B.Fab")
		)
		(fp_line
			(start -0.8128 -0.4572)
			(end -0.8128 0.4572)
			(stroke
				(width 0.1)
				(type default)
			)
			(layer "B.Fab")
		)
		(fp_line
			(start 0.8128 0.4572)
			(end 0.8128 -0.4572)
			(stroke
				(width 0.1)
				(type default)
			)
			(layer "B.Fab")
		)
		(fp_line
			(start -0.8128 0.4572)
			(end 0.8128 0.4572)
			(stroke
				(width 0.1)
				(type default)
			)
			(layer "B.Fab")
		)
		(pad "1" smd rect
			(at 0.6858 0 270)
			(size 0.762 0.8636)
			(layers "B.Cu" "B.Mask" "B.Paste")
			(net "VDD3V3_OSC_125M")
		)
		(pad "2" smd rect
			(at -0.6858 0 270)
			(size 0.762 0.8636)
			(layers "B.Cu" "B.Mask" "B.Paste")
			(net "XP3R3V")
		)
		(zone
			(layer "B.Cu")
			(hatch none 0.5)
			(connect_pads
				(clearance 0)
			)
			(min_thickness 0.25)
			(keepout
				(tracks not_allowed)
				(vias allowed)
				(pads allowed)
				(copperpour not_allowed)
				(footprints allowed)
			)
			(placement
				(enabled no)
				(sheetname "")
			)
			(fill
				(thermal_gap 0.5)
				(thermal_bridge_width 0.5)
				(island_removal_mode 0)
			)
			(polygon
				(pts
					(xy 96.2152 -22.7584) (xy 95.3008 -22.7584) (xy 95.3008 -22.4536) (xy 96.2152 -22.4536)
				)
			)
		)
		(zone
			(layer "B.Cu")
			(hatch none 0.5)
			(connect_pads
				(clearance 0)
			)
			(min_thickness 0.25)
			(keepout
				(tracks allowed)
				(vias not_allowed)
				(pads allowed)
				(copperpour not_allowed)
				(footprints allowed)
			)
			(placement
				(enabled no)
				(sheetname "")
			)
			(fill
				(thermal_gap 0.5)
				(thermal_bridge_width 0.5)
				(island_removal_mode 0)
			)
			(polygon
				(pts
					(xy 96.2152 -22.7584) (xy 95.3008 -22.7584) (xy 95.3008 -22.4536) (xy 96.2152 -22.4536)
				)
			)
		)
	)
	(footprint ""
		(layer "B.Cu")
		(at 95.631 -82.169 180)
		(property "Reference" "R191"
			(at 0.254 5.67563 0)
			(unlocked yes)
			(layer "B.SilkS")
			(effects
				(font
					(size 0.7874 0.5842)
					(thickness 0.1524)
				)
				(justify mirror)
			)
		)
		(property "Value" "VAL*"
			(at -0.02032 2.13233 180)
			(unlocked yes)
			(layer "B.Fab")
			(hide yes)
			(effects
				(font
					(size 0.7874 0.5842)
					(thickness 0.1524)
				)
				(justify mirror)
			)
		)
		(property "Device Type" "RESISTOR-G155-14701-01,4.7KOHMA"
			(at -0.008382 1.210564 180)
			(unlocked yes)
			(layer "B.Fab")
			(hide yes)
			(effects
				(font
					(size 0.7874 0.5842)
					(thickness 0.1524)
				)
				(justify mirror)
			)
		)
		(property "User Part Number" "PARTNUM*"
			(at -0.02032 4.024884 180)
			(unlocked yes)
			(layer "Cmts.User")
			(hide yes)
			(effects
				(font
					(size 0.7874 0.5842)
					(thickness 0.1524)
				)
				(justify mirror)
			)
		)
		(property "Tolerance" "TOL*"
			(at -0.044704 3.05435 180)
			(unlocked yes)
			(layer "Cmts.User")
			(hide yes)
			(effects
				(font
					(size 0.7874 0.5842)
					(thickness 0.1524)
				)
				(justify mirror)
			)
		)
		(duplicate_pad_numbers_are_jumpers no)
		(fp_line
			(start 1.143 0.5588)
			(end -1.143 0.5588)
			(stroke
				(width 0.1)
				(type default)
			)
			(layer "B.SilkS")
		)
		(fp_line
			(start 1.143 -0.5588)
			(end 1.143 0.5588)
			(stroke
				(width 0.1)
				(type default)
			)
			(layer "B.SilkS")
		)
		(fp_line
			(start -1.143 0.5588)
			(end -1.143 -0.5588)
			(stroke
				(width 0.1)
				(type default)
			)
			(layer "B.SilkS")
		)
		(fp_line
			(start -1.143 -0.5588)
			(end 1.143 -0.5588)
			(stroke
				(width 0.1)
				(type default)
			)
			(layer "B.SilkS")
		)
		(fp_rect
			(start 1.143 -0.5588)
			(end -1.143 0.5588)
			(stroke
				(width 0)
				(type default)
			)
			(fill no)
			(layer "B.CrtYd")
		)
		(fp_line
			(start 0.508 0.3048)
			(end -0.508 0.3048)
			(stroke
				(width 0.1)
				(type default)
			)
			(layer "B.Fab")
		)
		(fp_line
			(start 0.508 -0.3048)
			(end 0.508 0.3048)
			(stroke
				(width 0.1)
				(type default)
			)
			(layer "B.Fab")
		)
		(fp_line
			(start -0.508 0.3048)
			(end -0.508 -0.3048)
			(stroke
				(width 0.1)
				(type default)
			)
			(layer "B.Fab")
		)
		(fp_line
			(start -0.508 -0.3048)
			(end 0.508 -0.3048)
			(stroke
				(width 0.1)
				(type default)
			)
			(layer "B.Fab")
		)
		(pad "1" smd rect
			(at 0.5334 0)
			(size 0.7112 0.6096)
			(layers "B.Cu" "B.Mask" "B.Paste")
			(net "XP3R3V_FPGA")
		)
		(pad "2" smd rect
			(at -0.5334 0)
			(size 0.7112 0.6096)
			(layers "B.Cu" "B.Mask" "B.Paste")
			(net "FLASH_CS_N")
		)
		(zone
			(layer "B.Cu")
			(hatch none 0.5)
			(connect_pads
				(clearance 0)
			)
			(min_thickness 0.25)
			(keepout
				(tracks allowed)
				(vias not_allowed)
				(pads allowed)
				(copperpour not_allowed)
				(footprints allowed)
			)
			(placement
				(enabled no)
				(sheetname "")
			)
			(fill
				(thermal_gap 0.5)
				(thermal_bridge_width 0.5)
				(island_removal_mode 0)
			)
			(polygon
				(pts
					(xy 95.5548 -81.8642) (xy 95.7072 -81.8642) (xy 95.7072 -82.4738) (xy 95.5548 -82.4738)
				)
			)
		)
	)
)
